(kicad_pcb
	(version 20260206)
	(generator "pcbnew")
	(generator_version "10.0")
	(general
		(thickness 1.6)
		(legacy_teardrops no)
	)
	(paper "A4")
	(title_block
		(title "01162023_DA0F0TEBIF0_F0T_Expander_BD_F_brd_V02_OCP.brd")
		(comment 1 "Grand Teton / footprints 5605-5609 of 9728")
	)
	(layers
		(0 "F.Cu" signal "TOP")
		(4 "In1.Cu" signal "GND")
		(6 "In2.Cu" signal "VCC")
		(8 "In3.Cu" signal "VCC1")
		(10 "In4.Cu" signal "GND1")
		(12 "In5.Cu" signal "IN1")
		(14 "In6.Cu" signal "GND2")
		(16 "In7.Cu" signal "IN2")
		(18 "In8.Cu" signal "GND3")
		(20 "In9.Cu" signal "IN3")
		(22 "In10.Cu" signal "GND4")
		(24 "In11.Cu" signal "IN4")
		(26 "In12.Cu" signal "GND5")
		(28 "In13.Cu" signal "IN5")
		(30 "In14.Cu" signal "GND6")
		(32 "In15.Cu" signal "IN6")
		(34 "In16.Cu" signal "GND7")
		(2 "B.Cu" signal "BOTTOM")
		(9 "F.Adhes" user "F.Adhesive")
		(11 "B.Adhes" user "B.Adhesive")
		(13 "F.Paste" user "Package Geometry/Pastemask Top")
		(15 "B.Paste" user "Package Geometry/Pastemask Bottom")
		(5 "F.SilkS" user "Ref Des/Silkscreen Top")
		(7 "B.SilkS" user "Ref Des/Silkscreen Bottom")
		(1 "F.Mask" user "Board Geometry/Soldermask Top")
		(3 "B.Mask" user "Board Geometry/Soldermask Bottom")
		(17 "Dwgs.User" user "User.Drawings")
		(19 "Cmts.User" user "User.Comments")
		(21 "Eco1.User" user "User.Eco1")
		(23 "Eco2.User" user "User.Eco2")
		(25 "Edge.Cuts" user "Board Geometry/Outline")
		(27 "Margin" user)
		(31 "F.CrtYd" user "Package Geometry/Place Bound Top")
		(29 "B.CrtYd" user "Package Geometry/Place Bound Bottom")
		(35 "F.Fab" user "Ref Des/Assembly Top")
		(33 "B.Fab" user "Ref Des/Assembly Bottom")
	)
	(footprint ""
		(layer "F.Cu")
		(at 251.899674 -225.49993 180)
		(property "Reference" "JPEX2"
			(at -10.399522 -8.38454 0)
			(unlocked yes)
			(layer "F.SilkS")
			(effects
				(font
					(size 0.7874 0.5842)
					(thickness 0.1524)
				)
				(justify left)
			)
		)
		(property "Value" ""
			(at 0 0 180)
			(layer "F.Fab")
			(effects
				(font
					(size 1.27 1.27)
				)
			)
		)
		(duplicate_pad_numbers_are_jumpers no)
		(fp_line
			(start 12.46505 7.649972)
			(end -12.46505 7.649972)
			(stroke
				(width 0.1524)
				(type default)
			)
			(layer "F.SilkS")
		)
		(fp_line
			(start 12.46505 6.938264)
			(end 12.46505 7.649972)
			(stroke
				(width 0.1524)
				(type default)
			)
			(layer "F.SilkS")
		)
		(fp_line
			(start 12.46505 -4.827524)
			(end 12.46505 4.660138)
			(stroke
				(width 0.1524)
				(type default)
			)
			(layer "F.SilkS")
		)
		(fp_line
			(start 6.945122 7.649972)
			(end -6.945122 7.649972)
			(stroke
				(width 0.1524)
				(type default)
			)
			(layer "F.SilkS")
		)
		(fp_line
			(start 6.945122 -7.649972)
			(end 6.945122 7.649972)
			(stroke
				(width 0.1524)
				(type default)
			)
			(layer "F.SilkS")
		)
		(fp_line
			(start 6.945122 -7.649972)
			(end 0 -7.649972)
			(stroke
				(width 0.1524)
				(type default)
			)
			(layer "F.SilkS")
		)
		(fp_line
			(start 0 -7.649972)
			(end 9.858756 -7.649972)
			(stroke
				(width 0.1524)
				(type default)
			)
			(layer "F.SilkS")
		)
		(fp_line
			(start -6.945122 -7.649972)
			(end 0 -7.649972)
			(stroke
				(width 0.1524)
				(type default)
			)
			(layer "F.SilkS")
		)
		(fp_line
			(start -6.945122 -7.649972)
			(end -6.945122 7.649972)
			(stroke
				(width 0.1524)
				(type default)
			)
			(layer "F.SilkS")
		)
		(fp_line
			(start -12.46505 7.649972)
			(end -12.46505 -7.649972)
			(stroke
				(width 0.1524)
				(type default)
			)
			(layer "F.SilkS")
		)
		(fp_line
			(start -12.46505 -7.649972)
			(end 0 -7.649972)
			(stroke
				(width 0.1524)
				(type default)
			)
			(layer "F.SilkS")
		)
		(fp_poly
			(pts
				(xy -7.112 -4.445) (xy -8.128 -4.953) (xy -8.128 -3.937)
			)
			(stroke
				(width 0)
				(type default)
			)
			(fill yes)
			(layer "F.SilkS")
		)
		(fp_line
			(start 6.945122 7.649972)
			(end -6.945122 7.649972)
			(stroke
				(width 0.1)
				(type default)
			)
			(layer "F.Fab")
		)
		(fp_line
			(start 6.945122 -7.649972)
			(end 6.945122 7.649972)
			(stroke
				(width 0.1)
				(type default)
			)
			(layer "F.Fab")
		)
		(fp_line
			(start -6.945122 7.649972)
			(end -6.945122 -7.649972)
			(stroke
				(width 0.1)
				(type default)
			)
			(layer "F.Fab")
		)
		(fp_line
			(start -6.945122 -7.649972)
			(end 6.945122 -7.649972)
			(stroke
				(width 0.1)
				(type default)
			)
			(layer "F.Fab")
		)
		(fp_poly
			(pts
				(xy -7.112 -4.445) (xy -8.128 -4.953) (xy -8.128 -3.937)
			)
			(stroke
				(width 0)
				(type default)
			)
			(fill yes)
			(layer "F.Fab")
		)
		(fp_text user "9"
			(at 7.51713 4.1656 90)
			(unlocked yes)
			(layer "F.SilkS")
			(effects
				(font
					(size 0.7874 0.5842)
					(thickness 0.1524)
				)
				(justify left)
			)
		)
		(fp_text user "16"
			(at 7.49173 -5.2324 90)
			(unlocked yes)
			(layer "F.SilkS")
			(effects
				(font
					(size 0.7874 0.5842)
					(thickness 0.1524)
				)
				(justify left)
			)
		)
		(fp_text user "8"
			(at -7.77367 4.2164 90)
			(unlocked yes)
			(layer "F.SilkS")
			(effects
				(font
					(size 0.7874 0.5842)
					(thickness 0.1524)
				)
				(justify left)
			)
		)
		(fp_text user "9"
			(at 7.51713 4.1656 90)
			(unlocked yes)
			(layer "F.Fab")
			(effects
				(font
					(size 0.7874 0.5842)
					(thickness 0.1524)
				)
				(justify left)
			)
		)
		(fp_text user "16"
			(at 7.49173 -5.2324 90)
			(unlocked yes)
			(layer "F.Fab")
			(effects
				(font
					(size 0.7874 0.5842)
					(thickness 0.1524)
				)
				(justify left)
			)
		)
		(fp_text user "8"
			(at -7.77367 4.2164 90)
			(unlocked yes)
			(layer "F.Fab")
			(effects
				(font
					(size 0.7874 0.5842)
					(thickness 0.1524)
				)
				(justify left)
			)
		)
		(pad "1" smd rect
			(at -4.800092 -4.445 90)
			(size 0.508 1.524)
			(layers "F.Cu" "F.Mask" "F.Paste")
			(net "SPI_PEX2_SDIO3_R1")
		)
		(pad "2" smd rect
			(at -4.800092 -3.175 90)
			(size 0.508 1.524)
			(layers "F.Cu" "F.Mask" "F.Paste")
			(net "P1V8_PEX")
		)
		(pad "3" smd rect
			(at -4.800092 -1.905 90)
			(size 0.508 1.524)
			(layers "F.Cu" "F.Mask" "F.Paste")
			(net "SPI_PEX2_RST_R_N")
		)
		(pad "4" smd rect
			(at -4.800092 -0.635 90)
			(size 0.508 1.524)
			(layers "F.Cu" "F.Mask" "F.Paste")
			(net "Net_2698")
		)
		(pad "5" smd rect
			(at -4.800092 0.635 90)
			(size 0.508 1.524)
			(layers "F.Cu" "F.Mask" "F.Paste")
			(net "Net_2697")
		)
		(pad "6" smd rect
			(at -4.800092 1.905 90)
			(size 0.508 1.524)
			(layers "F.Cu" "F.Mask" "F.Paste")
			(net "Net_2696")
		)
		(pad "7" smd rect
			(at -4.800092 3.175 90)
			(size 0.508 1.524)
			(layers "F.Cu" "F.Mask" "F.Paste")
			(net "SPI_PEX2_CS_MUX_R_N")
		)
		(pad "8" smd rect
			(at -4.800092 4.445 90)
			(size 0.508 1.524)
			(layers "F.Cu" "F.Mask" "F.Paste")
			(net "SPI_PEX2_SDIO1_MUX_R")
		)
		(pad "9" smd rect
			(at 4.800092 4.445 90)
			(size 0.508 1.524)
			(layers "F.Cu" "F.Mask" "F.Paste")
			(net "SPI_PEX2_SDIO2_R1")
		)
		(pad "10" smd rect
			(at 4.800092 3.175 90)
			(size 0.508 1.524)
			(layers "F.Cu" "F.Mask" "F.Paste")
			(net "GND")
		)
		(pad "11" smd rect
			(at 4.800092 1.905 90)
			(size 0.508 1.524)
			(layers "F.Cu" "F.Mask" "F.Paste")
			(net "Net_2699")
		)
		(pad "12" smd rect
			(at 4.800092 0.635 90)
			(size 0.508 1.524)
			(layers "F.Cu" "F.Mask" "F.Paste")
			(net "Net_2700")
		)
		(pad "13" smd rect
			(at 4.800092 -0.635 90)
			(size 0.508 1.524)
			(layers "F.Cu" "F.Mask" "F.Paste")
			(net "Net_2701")
		)
		(pad "14" smd rect
			(at 4.800092 -1.905 90)
			(size 0.508 1.524)
			(layers "F.Cu" "F.Mask" "F.Paste")
			(net "Net_2702")
		)
		(pad "15" smd rect
			(at 4.800092 -3.175 90)
			(size 0.508 1.524)
			(layers "F.Cu" "F.Mask" "F.Paste")
			(net "SPI_PEX2_SDIO0_MUX_R")
		)
		(pad "16" smd rect
			(at 4.800092 -4.445 90)
			(size 0.508 1.524)
			(layers "F.Cu" "F.Mask" "F.Paste")
			(net "SPI_PEX2_CLK_MUX_R")
		)
	)
	(footprint ""
		(layer "F.Cu")
		(at 278.714454 -66.32194 90)
		(property "Reference" "R5991"
			(at 0 0 90)
			(layer "F.SilkS")
			(hide yes)
			(effects
				(font
					(size 1.27 1.27)
				)
			)
		)
		(property "Value" ""
			(at 0 0 90)
			(layer "F.Fab")
			(effects
				(font
					(size 1.27 1.27)
				)
			)
		)
		(duplicate_pad_numbers_are_jumpers no)
		(fp_line
			(start 0.7874 -0.4064)
			(end 0.7874 0.4064)
			(stroke
				(width 0.1524)
				(type default)
			)
			(layer "F.SilkS")
		)
		(fp_line
			(start -0.7874 -0.4064)
			(end 0.7874 -0.4064)
			(stroke
				(width 0.1524)
				(type default)
			)
			(layer "F.SilkS")
		)
		(fp_line
			(start 0.7874 0.4064)
			(end -0.7874 0.4064)
			(stroke
				(width 0.1524)
				(type default)
			)
			(layer "F.SilkS")
		)
		(fp_line
			(start -0.7874 0.4064)
			(end -0.7874 -0.4064)
			(stroke
				(width 0.1524)
				(type default)
			)
			(layer "F.SilkS")
		)
		(fp_line
			(start -0.12065 -0.305054)
			(end -0.12065 -0.2794)
			(stroke
				(width 0.1)
				(type default)
			)
			(layer "F.Fab")
		)
		(fp_line
			(start -0.67945 -0.305054)
			(end -0.12065 -0.305054)
			(stroke
				(width 0.1)
				(type default)
			)
			(layer "F.Fab")
		)
		(fp_line
			(start 0.67945 -0.3048)
			(end 0.67945 0.3048)
			(stroke
				(width 0.1)
				(type default)
			)
			(layer "F.Fab")
		)
		(fp_line
			(start 0.12065 -0.3048)
			(end 0.67945 -0.3048)
			(stroke
				(width 0.1)
				(type default)
			)
			(layer "F.Fab")
		)
		(fp_line
			(start 0.12065 -0.2794)
			(end 0.12065 -0.3048)
			(stroke
				(width 0.1)
				(type default)
			)
			(layer "F.Fab")
		)
		(fp_line
			(start -0.12065 -0.2794)
			(end 0.12065 -0.2794)
			(stroke
				(width 0.1)
				(type default)
			)
			(layer "F.Fab")
		)
		(fp_line
			(start 0.120396 0.2794)
			(end -0.12065 0.2794)
			(stroke
				(width 0.1)
				(type default)
			)
			(layer "F.Fab")
		)
		(fp_line
			(start -0.12065 0.2794)
			(end -0.12065 0.3048)
			(stroke
				(width 0.1)
				(type default)
			)
			(layer "F.Fab")
		)
		(fp_line
			(start 0.67945 0.3048)
			(end 0.120396 0.3048)
			(stroke
				(width 0.1)
				(type default)
			)
			(layer "F.Fab")
		)
		(fp_line
			(start 0.120396 0.3048)
			(end 0.120396 0.2794)
			(stroke
				(width 0.1)
				(type default)
			)
			(layer "F.Fab")
		)
		(fp_line
			(start -0.12065 0.3048)
			(end -0.67945 0.3048)
			(stroke
				(width 0.1)
				(type default)
			)
			(layer "F.Fab")
		)
		(fp_line
			(start -0.67945 0.3048)
			(end -0.67945 -0.305054)
			(stroke
				(width 0.1)
				(type default)
			)
			(layer "F.Fab")
		)
		(pad "1" smd circle
			(at -0.40005 0 90)
			(size 0 0)
			(layers "F.Cu" "F.Mask" "F.Paste")
			(net "SSD9_PWR_EN_R")
		)
		(pad "2" smd circle
			(at 0.40005 0 90)
			(size 0 0)
			(layers "F.Cu" "F.Mask" "F.Paste")
			(net "P12V_SSD9_CO_EN")
		)
	)
	(footprint ""
		(layer "F.Cu")
		(at 134.779766 -135.62711 90)
		(property "Reference" "PD14"
			(at -3.34391 2.178304 90)
			(unlocked yes)
			(layer "F.SilkS")
			(effects
				(font
					(size 0.7874 0.5842)
					(thickness 0.1524)
				)
				(justify left)
			)
		)
		(property "Value" ""
			(at 0 0 90)
			(layer "F.Fab")
			(effects
				(font
					(size 1.27 1.27)
				)
			)
		)
		(duplicate_pad_numbers_are_jumpers no)
		(fp_line
			(start 4.107942 -1.459992)
			(end 4.107942 1.459992)
			(stroke
				(width 0.1524)
				(type default)
			)
			(layer "F.SilkS")
		)
		(fp_line
			(start -3.400044 -1.459992)
			(end 4.107942 -1.459992)
			(stroke
				(width 0.1524)
				(type default)
			)
			(layer "F.SilkS")
		)
		(fp_line
			(start 4.107942 1.459992)
			(end -3.400044 1.459992)
			(stroke
				(width 0.1524)
				(type default)
			)
			(layer "F.SilkS")
		)
		(fp_line
			(start -3.400044 1.459992)
			(end -3.400044 -1.459992)
			(stroke
				(width 0.1524)
				(type default)
			)
			(layer "F.SilkS")
		)
		(fp_poly
			(pts
				(xy 4.107942 -1.459992) (xy 4.107942 1.459992) (xy 3.308096 1.459992) (xy 3.308096 -1.459992)
			)
			(stroke
				(width 0)
				(type default)
			)
			(fill yes)
			(layer "F.SilkS")
		)
		(fp_line
			(start 2.29997 -1.459992)
			(end 2.29997 1.459992)
			(stroke
				(width 0.1)
				(type default)
			)
			(layer "F.Fab")
		)
		(fp_line
			(start -2.29997 -1.459992)
			(end 2.29997 -1.459992)
			(stroke
				(width 0.1)
				(type default)
			)
			(layer "F.Fab")
		)
		(fp_line
			(start 2.29997 1.459992)
			(end -2.29997 1.459992)
			(stroke
				(width 0.1)
				(type default)
			)
			(layer "F.Fab")
		)
		(fp_line
			(start -2.29997 1.459992)
			(end -2.29997 -1.459992)
			(stroke
				(width 0.1)
				(type default)
			)
			(layer "F.Fab")
		)
		(fp_text user "+"
			(at -4.7752 -0.12065 90)
			(unlocked yes)
			(layer "F.SilkS")
			(effects
				(font
					(size 1.905 1.4224)
					(thickness 0.1524)
				)
				(justify left)
			)
		)
		(fp_text user "-"
			(at 4.8006 2.191766 270)
			(unlocked yes)
			(layer "F.SilkS")
			(effects
				(font
					(size 1.905 1.4224)
					(thickness 0.1524)
				)
				(justify left)
			)
		)
		(fp_text user "+"
			(at -4.7752 -0.12065 90)
			(unlocked yes)
			(layer "F.Fab")
			(effects
				(font
					(size 1.905 1.4224)
					(thickness 0.1524)
				)
				(justify left)
			)
		)
		(fp_text user "-"
			(at 5.4102 0.29845 270)
			(unlocked yes)
			(layer "F.Fab")
			(effects
				(font
					(size 1.905 1.4224)
					(thickness 0.1524)
				)
				(justify left)
			)
		)
		(pad "A" smd rect
			(at -1.999996 0 180)
			(size 1.7018 2.5146)
			(layers "F.Cu" "F.Mask" "F.Paste")
			(net "GND")
		)
		(pad "C" smd rect
			(at 1.999996 0 180)
			(size 1.7018 2.5146)
			(layers "F.Cu" "F.Mask" "F.Paste")
			(net "P12V_NIC2_R")
		)
	)
	(footprint ""
		(layer "F.Cu")
		(at 437.250332 -350.098614 90)
		(property "Reference" "C798"
			(at 0 0 90)
			(layer "F.SilkS")
			(hide yes)
			(effects
				(font
					(size 1.27 1.27)
				)
			)
		)
		(property "Value" ""
			(at 0 0 90)
			(layer "F.Fab")
			(effects
				(font
					(size 1.27 1.27)
				)
			)
		)
		(duplicate_pad_numbers_are_jumpers no)
		(fp_line
			(start 0.299974 -0.150114)
			(end 0.299974 0.150114)
			(stroke
				(width 0.1)
				(type default)
			)
			(layer "F.Fab")
		)
		(fp_line
			(start -0.299974 -0.150114)
			(end 0.299974 -0.150114)
			(stroke
				(width 0.1)
				(type default)
			)
			(layer "F.Fab")
		)
		(fp_line
			(start 0.299974 0.150114)
			(end -0.299974 0.150114)
			(stroke
				(width 0.1)
				(type default)
			)
			(layer "F.Fab")
		)
		(fp_line
			(start -0.299974 0.150114)
			(end -0.299974 -0.150114)
			(stroke
				(width 0.1)
				(type default)
			)
			(layer "F.Fab")
		)
		(pad "1" smd rect
			(at -0.2667 0 90)
			(size 0.3048 0.381)
			(layers "F.Cu" "F.Mask" "F.Paste")
			(net "P5E_PEX3_STN7_TX_DP<125>")
		)
		(pad "2" smd rect
			(at 0.2667 0 90)
			(size 0.3048 0.381)
			(layers "F.Cu" "F.Mask" "F.Paste")
			(net "P5E_PEX3_STN7_TX_C_DP<125>")
		)
	)
	(footprint ""
		(layer "F.Cu")
		(at 194.559428 -22.955504 90)
		(property "Reference" "R1685"
			(at 0 0 90)
			(layer "F.SilkS")
			(hide yes)
			(effects
				(font
					(size 1.27 1.27)
				)
			)
		)
		(property "Value" ""
			(at 0 0 90)
			(layer "F.Fab")
			(effects
				(font
					(size 1.27 1.27)
				)
			)
		)
		(duplicate_pad_numbers_are_jumpers no)
		(fp_line
			(start 0.7874 -0.4064)
			(end 0.7874 0.4064)
			(stroke
				(width 0.1524)
				(type default)
			)
			(layer "F.SilkS")
		)
		(fp_line
			(start -0.7874 -0.4064)
			(end 0.7874 -0.4064)
			(stroke
				(width 0.1524)
				(type default)
			)
			(layer "F.SilkS")
		)
		(fp_line
			(start 0.7874 0.4064)
			(end -0.7874 0.4064)
			(stroke
				(width 0.1524)
				(type default)
			)
			(layer "F.SilkS")
		)
		(fp_line
			(start -0.7874 0.4064)
			(end -0.7874 -0.4064)
			(stroke
				(width 0.1524)
				(type default)
			)
			(layer "F.SilkS")
		)
		(fp_line
			(start -0.12065 -0.305054)
			(end -0.12065 -0.2794)
			(stroke
				(width 0.1)
				(type default)
			)
			(layer "F.Fab")
		)
		(fp_line
			(start -0.67945 -0.305054)
			(end -0.12065 -0.305054)
			(stroke
				(width 0.1)
				(type default)
			)
			(layer "F.Fab")
		)
		(fp_line
			(start 0.67945 -0.3048)
			(end 0.67945 0.3048)
			(stroke
				(width 0.1)
				(type default)
			)
			(layer "F.Fab")
		)
		(fp_line
			(start 0.12065 -0.3048)
			(end 0.67945 -0.3048)
			(stroke
				(width 0.1)
				(type default)
			)
			(layer "F.Fab")
		)
		(fp_line
			(start 0.12065 -0.2794)
			(end 0.12065 -0.3048)
			(stroke
				(width 0.1)
				(type default)
			)
			(layer "F.Fab")
		)
		(fp_line
			(start -0.12065 -0.2794)
			(end 0.12065 -0.2794)
			(stroke
				(width 0.1)
				(type default)
			)
			(layer "F.Fab")
		)
		(fp_line
			(start 0.120396 0.2794)
			(end -0.12065 0.2794)
			(stroke
				(width 0.1)
				(type default)
			)
			(layer "F.Fab")
		)
		(fp_line
			(start -0.12065 0.2794)
			(end -0.12065 0.3048)
			(stroke
				(width 0.1)
				(type default)
			)
			(layer "F.Fab")
		)
		(fp_line
			(start 0.67945 0.3048)
			(end 0.120396 0.3048)
			(stroke
				(width 0.1)
				(type default)
			)
			(layer "F.Fab")
		)
		(fp_line
			(start 0.120396 0.3048)
			(end 0.120396 0.2794)
			(stroke
				(width 0.1)
				(type default)
			)
			(layer "F.Fab")
		)
		(fp_line
			(start -0.12065 0.3048)
			(end -0.67945 0.3048)
			(stroke
				(width 0.1)
				(type default)
			)
			(layer "F.Fab")
		)
		(fp_line
			(start -0.67945 0.3048)
			(end -0.67945 -0.305054)
			(stroke
				(width 0.1)
				(type default)
			)
			(layer "F.Fab")
		)
		(pad "1" smd circle
			(at -0.40005 0 90)
			(size 0 0)
			(layers "F.Cu" "F.Mask" "F.Paste")
			(net "SMB_BIC_I2C9_MUX0_SSD6_R_SCL")
		)
		(pad "2" smd circle
			(at 0.40005 0 90)
			(size 0 0)
			(layers "F.Cu" "F.Mask" "F.Paste")
			(net "SMB_ISO_SSD6_SCL")
		)
	)
)
